(kicad_pcb
	(version 20241229)
	(generator "pcbnew")
	(generator_version "9.0")
	(general
		(thickness 1.599998)
		(legacy_teardrops no)
	)
	(paper "A4")
	(title_block
		(title "Artix - Datacenter Secure Control Module (DC-SCM)")
		(date "2024-11-06")
		(rev "1.1.3")
		(comment 9 "footprints 448-452 of 544")
	)
	(layers
		(0 "F.Cu" signal)
		(4 "In1.Cu" signal)
		(6 "In2.Cu" signal)
		(8 "In3.Cu" signal)
		(10 "In4.Cu" signal)
		(12 "In5.Cu" signal)
		(14 "In6.Cu" signal)
		(2 "B.Cu" signal)
		(9 "F.Adhes" user "F.Adhesive")
		(11 "B.Adhes" user "B.Adhesive")
		(13 "F.Paste" user)
		(15 "B.Paste" user)
		(5 "F.SilkS" user "F.Silkscreen")
		(7 "B.SilkS" user "B.Silkscreen")
		(1 "F.Mask" user)
		(3 "B.Mask" user)
		(17 "Dwgs.User" user "User.Drawings")
		(19 "Cmts.User" user "User.Comments")
		(21 "Eco1.User" user "User.Eco1")
		(23 "Eco2.User" user "User.Eco2")
		(25 "Edge.Cuts" user)
		(27 "Margin" user)
		(31 "F.CrtYd" user "F.Courtyard")
		(29 "B.CrtYd" user "B.Courtyard")
		(35 "F.Fab" user)
		(33 "B.Fab" user)
	)
	(footprint "antmicro-footprints:C_0402_1005Metric"
		(layer "B.Cu")
		(at 140.274 131.414 180)
		(descr "Capacitor SMD 0402")
		(tags "capacitor SMD 0402")
		(property "Reference" "C189"
			(at -3.726 -0.386 0)
			(layer "B.SilkS")
			(effects
				(font
					(size 0.7 0.7)
					(thickness 0.15)
				)
				(justify left bottom mirror)
			)
		)
		(property "Value" "C_100n_6V3_0402"
			(at 0 -1.4 0)
			(layer "B.Fab")
			(effects
				(font
					(size 0.7 0.7)
					(thickness 0.15)
				)
				(justify left bottom mirror)
			)
		)
		(property "Datasheet" "https://www.passivecomponent.com/wp-content/uploads/datasheet/WTC_MLCC_General_Purpose.pdf"
			(at 0 0 180)
			(layer "F.Fab")
			(hide yes)
			(effects
				(font
					(size 1.27 1.27)
					(thickness 0.15)
				)
			)
		)
		(property "Description" "SMT Multilayer Ceramic Capacitor, 0.1 µF, 6.3 V, 0402 [1005 Metric], ± 10%, X5R, Walsin MLCC"
			(at 0 0 180)
			(layer "F.Fab")
			(hide yes)
			(effects
				(font
					(size 1.27 1.27)
					(thickness 0.15)
				)
			)
		)
		(property "Author" "Antmicro"
			(at 280.548 262.828 0)
			(layer "B.Fab")
			(hide yes)
			(effects
				(font
					(size 1 1)
					(thickness 0.15)
				)
				(justify mirror)
			)
		)
		(property "Dielectric" ""
			(at 280.548 262.828 0)
			(layer "B.Fab")
			(hide yes)
			(effects
				(font
					(size 1 1)
					(thickness 0.15)
				)
				(justify mirror)
			)
		)
		(property "License" "Apache-2.0"
			(at 280.548 262.828 0)
			(layer "B.Fab")
			(hide yes)
			(effects
				(font
					(size 1 1)
					(thickness 0.15)
				)
				(justify mirror)
			)
		)
		(property "MPN" "0402X104K6R3CT"
			(at 280.548 262.828 0)
			(layer "B.Fab")
			(hide yes)
			(effects
				(font
					(size 1 1)
					(thickness 0.15)
				)
				(justify mirror)
			)
		)
		(property "Manufacturer" "Walsin"
			(at 280.548 262.828 0)
			(layer "B.Fab")
			(hide yes)
			(effects
				(font
					(size 1 1)
					(thickness 0.15)
				)
				(justify mirror)
			)
		)
		(property "Public" "False"
			(at 280.548 262.828 0)
			(layer "B.Fab")
			(hide yes)
			(effects
				(font
					(size 1 1)
					(thickness 0.15)
				)
				(justify mirror)
			)
		)
		(property "Val" "100n"
			(at 280.548 262.828 0)
			(layer "B.Fab")
			(hide yes)
			(effects
				(font
					(size 1 1)
					(thickness 0.15)
				)
				(justify mirror)
			)
		)
		(property "Voltage" ""
			(at 280.548 262.828 0)
			(layer "B.Fab")
			(hide yes)
			(effects
				(font
					(size 1 1)
					(thickness 0.15)
				)
				(justify mirror)
			)
		)
		(sheetname "/Interfaces/")
		(sheetfile "interfaces.kicad_sch")
		(attr smd)
		(fp_rect
			(start -0.925 0.47)
			(end 0.925 -0.47)
			(stroke
				(width 0.05)
				(type default)
			)
			(fill no)
			(layer "B.CrtYd")
		)
		(fp_line
			(start 0.504 0.25)
			(end 0.504 -0.248)
			(stroke
				(width 0.15)
				(type solid)
			)
			(layer "B.Fab")
		)
		(fp_line
			(start 0.504 -0.248)
			(end -0.494 -0.248)
			(stroke
				(width 0.15)
				(type solid)
			)
			(layer "B.Fab")
		)
		(fp_line
			(start -0.494 0.25)
			(end 0.504 0.25)
			(stroke
				(width 0.15)
				(type solid)
			)
			(layer "B.Fab")
		)
		(fp_line
			(start -0.494 -0.248)
			(end -0.494 0.25)
			(stroke
				(width 0.15)
				(type solid)
			)
			(layer "B.Fab")
		)
		(pad "1" smd roundrect
			(at -0.48 0 180)
			(size 0.59 0.64)
			(layers "B.Cu" "B.Mask" "B.Paste")
			(roundrect_rratio 0.25)
			(net 1 "GND")
			(pintype "passive")
		)
		(pad "2" smd roundrect
			(at 0.48 0 180)
			(size 0.59 0.64)
			(layers "B.Cu" "B.Mask" "B.Paste")
			(roundrect_rratio 0.25)
			(net 200 "Net-(U1-VDDIM)")
			(pintype "passive")
		)
	)
	(footprint "antmicro-footprints:C_0402_1005Metric"
		(layer "B.Cu")
		(at 138.774 127.514 -90)
		(descr "Capacitor SMD 0402")
		(tags "capacitor SMD 0402")
		(property "Reference" "C223"
			(at 1.086 2.974 90)
			(layer "B.SilkS")
			(effects
				(font
					(size 0.7 0.7)
					(thickness 0.15)
				)
				(justify left bottom mirror)
			)
		)
		(property "Value" "C_100n_6V3_0402"
			(at 0 -1.4 90)
			(layer "B.Fab")
			(effects
				(font
					(size 0.7 0.7)
					(thickness 0.15)
				)
				(justify left bottom mirror)
			)
		)
		(property "Datasheet" "https://www.passivecomponent.com/wp-content/uploads/datasheet/WTC_MLCC_General_Purpose.pdf"
			(at 0 0 270)
			(layer "F.Fab")
			(hide yes)
			(effects
				(font
					(size 1.27 1.27)
					(thickness 0.15)
				)
			)
		)
		(property "Description" "SMT Multilayer Ceramic Capacitor, 0.1 µF, 6.3 V, 0402 [1005 Metric], ± 10%, X5R, Walsin MLCC"
			(at 0 0 270)
			(layer "F.Fab")
			(hide yes)
			(effects
				(font
					(size 1.27 1.27)
					(thickness 0.15)
				)
			)
		)
		(property "Author" "Antmicro"
			(at 11.26 266.288 0)
			(layer "B.Fab")
			(hide yes)
			(effects
				(font
					(size 1 1)
					(thickness 0.15)
				)
				(justify mirror)
			)
		)
		(property "Dielectric" ""
			(at 11.26 266.288 0)
			(layer "B.Fab")
			(hide yes)
			(effects
				(font
					(size 1 1)
					(thickness 0.15)
				)
				(justify mirror)
			)
		)
		(property "License" "Apache-2.0"
			(at 11.26 266.288 0)
			(layer "B.Fab")
			(hide yes)
			(effects
				(font
					(size 1 1)
					(thickness 0.15)
				)
				(justify mirror)
			)
		)
		(property "MPN" "0402X104K6R3CT"
			(at 11.26 266.288 0)
			(layer "B.Fab")
			(hide yes)
			(effects
				(font
					(size 1 1)
					(thickness 0.15)
				)
				(justify mirror)
			)
		)
		(property "Manufacturer" "Walsin"
			(at 11.26 266.288 0)
			(layer "B.Fab")
			(hide yes)
			(effects
				(font
					(size 1 1)
					(thickness 0.15)
				)
				(justify mirror)
			)
		)
		(property "Public" "False"
			(at 11.26 266.288 0)
			(layer "B.Fab")
			(hide yes)
			(effects
				(font
					(size 1 1)
					(thickness 0.15)
				)
				(justify mirror)
			)
		)
		(property "Val" "100n"
			(at 11.26 266.288 0)
			(layer "B.Fab")
			(hide yes)
			(effects
				(font
					(size 1 1)
					(thickness 0.15)
				)
				(justify mirror)
			)
		)
		(property "Voltage" ""
			(at 11.26 266.288 0)
			(layer "B.Fab")
			(hide yes)
			(effects
				(font
					(size 1 1)
					(thickness 0.15)
				)
				(justify mirror)
			)
		)
		(sheetname "/Interfaces/")
		(sheetfile "interfaces.kicad_sch")
		(attr smd)
		(fp_rect
			(start -0.925 0.47)
			(end 0.925 -0.47)
			(stroke
				(width 0.05)
				(type default)
			)
			(fill no)
			(layer "B.CrtYd")
		)
		(fp_line
			(start -0.494 0.25)
			(end 0.504 0.25)
			(stroke
				(width 0.15)
				(type solid)
			)
			(layer "B.Fab")
		)
		(fp_line
			(start 0.504 0.25)
			(end 0.504 -0.248)
			(stroke
				(width 0.15)
				(type solid)
			)
			(layer "B.Fab")
		)
		(fp_line
			(start -0.494 -0.248)
			(end -0.494 0.25)
			(stroke
				(width 0.15)
				(type solid)
			)
			(layer "B.Fab")
		)
		(fp_line
			(start 0.504 -0.248)
			(end -0.494 -0.248)
			(stroke
				(width 0.15)
				(type solid)
			)
			(layer "B.Fab")
		)
		(pad "1" smd roundrect
			(at -0.48 0 270)
			(size 0.59 0.64)
			(layers "B.Cu" "B.Mask" "B.Paste")
			(roundrect_rratio 0.25)
			(net 1 "GND")
			(pintype "passive")
		)
		(pad "2" smd roundrect
			(at 0.48 0 270)
			(size 0.59 0.64)
			(layers "B.Cu" "B.Mask" "B.Paste")
			(roundrect_rratio 0.25)
			(net 2 "VCC3V3")
			(pintype "passive")
		)
	)
	(footprint "antmicro-footprints:C_0402_1005Metric"
		(layer "B.Cu")
		(at 133.775 127.515 -90)
		(descr "Capacitor SMD 0402")
		(tags "capacitor SMD 0402")
		(property "Reference" "C224"
			(at 1.086 2.974 90)
			(layer "B.SilkS")
			(effects
				(font
					(size 0.7 0.7)
					(thickness 0.15)
				)
				(justify left bottom mirror)
			)
		)
		(property "Value" "C_100n_6V3_0402"
			(at 0 -1.4 90)
			(layer "B.Fab")
			(effects
				(font
					(size 0.7 0.7)
					(thickness 0.15)
				)
				(justify left bottom mirror)
			)
		)
		(property "Datasheet" "https://www.passivecomponent.com/wp-content/uploads/datasheet/WTC_MLCC_General_Purpose.pdf"
			(at 0 0 270)
			(layer "F.Fab")
			(hide yes)
			(effects
				(font
					(size 1.27 1.27)
					(thickness 0.15)
				)
			)
		)
		(property "Description" "SMT Multilayer Ceramic Capacitor, 0.1 µF, 6.3 V, 0402 [1005 Metric], ± 10%, X5R, Walsin MLCC"
			(at 0 0 270)
			(layer "F.Fab")
			(hide yes)
			(effects
				(font
					(size 1.27 1.27)
					(thickness 0.15)
				)
			)
		)
		(property "Author" "Antmicro"
			(at 6.26 261.29 0)
			(layer "B.Fab")
			(hide yes)
			(effects
				(font
					(size 1 1)
					(thickness 0.15)
				)
				(justify mirror)
			)
		)
		(property "Dielectric" ""
			(at 6.26 261.29 0)
			(layer "B.Fab")
			(hide yes)
			(effects
				(font
					(size 1 1)
					(thickness 0.15)
				)
				(justify mirror)
			)
		)
		(property "License" "Apache-2.0"
			(at 6.26 261.29 0)
			(layer "B.Fab")
			(hide yes)
			(effects
				(font
					(size 1 1)
					(thickness 0.15)
				)
				(justify mirror)
			)
		)
		(property "MPN" "0402X104K6R3CT"
			(at 6.26 261.29 0)
			(layer "B.Fab")
			(hide yes)
			(effects
				(font
					(size 1 1)
					(thickness 0.15)
				)
				(justify mirror)
			)
		)
		(property "Manufacturer" "Walsin"
			(at 6.26 261.29 0)
			(layer "B.Fab")
			(hide yes)
			(effects
				(font
					(size 1 1)
					(thickness 0.15)
				)
				(justify mirror)
			)
		)
		(property "Public" "False"
			(at 6.26 261.29 0)
			(layer "B.Fab")
			(hide yes)
			(effects
				(font
					(size 1 1)
					(thickness 0.15)
				)
				(justify mirror)
			)
		)
		(property "Val" "100n"
			(at 6.26 261.29 0)
			(layer "B.Fab")
			(hide yes)
			(effects
				(font
					(size 1 1)
					(thickness 0.15)
				)
				(justify mirror)
			)
		)
		(property "Voltage" ""
			(at 6.26 261.29 0)
			(layer "B.Fab")
			(hide yes)
			(effects
				(font
					(size 1 1)
					(thickness 0.15)
				)
				(justify mirror)
			)
		)
		(sheetname "/Interfaces/")
		(sheetfile "interfaces.kicad_sch")
		(attr smd)
		(fp_rect
			(start -0.925 0.47)
			(end 0.925 -0.47)
			(stroke
				(width 0.05)
				(type default)
			)
			(fill no)
			(layer "B.CrtYd")
		)
		(fp_line
			(start -0.494 0.25)
			(end 0.504 0.25)
			(stroke
				(width 0.15)
				(type solid)
			)
			(layer "B.Fab")
		)
		(fp_line
			(start 0.504 0.25)
			(end 0.504 -0.248)
			(stroke
				(width 0.15)
				(type solid)
			)
			(layer "B.Fab")
		)
		(fp_line
			(start -0.494 -0.248)
			(end -0.494 0.25)
			(stroke
				(width 0.15)
				(type solid)
			)
			(layer "B.Fab")
		)
		(fp_line
			(start 0.504 -0.248)
			(end -0.494 -0.248)
			(stroke
				(width 0.15)
				(type solid)
			)
			(layer "B.Fab")
		)
		(pad "1" smd roundrect
			(at -0.48 0 270)
			(size 0.59 0.64)
			(layers "B.Cu" "B.Mask" "B.Paste")
			(roundrect_rratio 0.25)
			(net 1 "GND")
			(pintype "passive")
		)
		(pad "2" smd roundrect
			(at 0.48 0 270)
			(size 0.59 0.64)
			(layers "B.Cu" "B.Mask" "B.Paste")
			(roundrect_rratio 0.25)
			(net 2 "VCC3V3")
			(pintype "passive")
		)
	)
	(footprint "antmicro-footprints:C_0402_1005Metric"
		(layer "B.Cu")
		(at 139.774 127.514 -90)
		(descr "Capacitor SMD 0402")
		(tags "capacitor SMD 0402")
		(property "Reference" "C229"
			(at 1.086 2.974 90)
			(layer "B.SilkS")
			(effects
				(font
					(size 0.7 0.7)
					(thickness 0.15)
				)
				(justify left bottom mirror)
			)
		)
		(property "Value" "C_100n_6V3_0402"
			(at 0 -1.4 90)
			(layer "B.Fab")
			(effects
				(font
					(size 0.7 0.7)
					(thickness 0.15)
				)
				(justify left bottom mirror)
			)
		)
		(property "Datasheet" "https://www.passivecomponent.com/wp-content/uploads/datasheet/WTC_MLCC_General_Purpose.pdf"
			(at 0 0 270)
			(layer "F.Fab")
			(hide yes)
			(effects
				(font
					(size 1.27 1.27)
					(thickness 0.15)
				)
			)
		)
		(property "Description" "SMT Multilayer Ceramic Capacitor, 0.1 µF, 6.3 V, 0402 [1005 Metric], ± 10%, X5R, Walsin MLCC"
			(at 0 0 270)
			(layer "F.Fab")
			(hide yes)
			(effects
				(font
					(size 1.27 1.27)
					(thickness 0.15)
				)
			)
		)
		(property "Author" "Antmicro"
			(at 12.26 267.288 0)
			(layer "B.Fab")
			(hide yes)
			(effects
				(font
					(size 1 1)
					(thickness 0.15)
				)
				(justify mirror)
			)
		)
		(property "Dielectric" ""
			(at 12.26 267.288 0)
			(layer "B.Fab")
			(hide yes)
			(effects
				(font
					(size 1 1)
					(thickness 0.15)
				)
				(justify mirror)
			)
		)
		(property "License" "Apache-2.0"
			(at 12.26 267.288 0)
			(layer "B.Fab")
			(hide yes)
			(effects
				(font
					(size 1 1)
					(thickness 0.15)
				)
				(justify mirror)
			)
		)
		(property "MPN" "0402X104K6R3CT"
			(at 12.26 267.288 0)
			(layer "B.Fab")
			(hide yes)
			(effects
				(font
					(size 1 1)
					(thickness 0.15)
				)
				(justify mirror)
			)
		)
		(property "Manufacturer" "Walsin"
			(at 12.26 267.288 0)
			(layer "B.Fab")
			(hide yes)
			(effects
				(font
					(size 1 1)
					(thickness 0.15)
				)
				(justify mirror)
			)
		)
		(property "Public" "False"
			(at 12.26 267.288 0)
			(layer "B.Fab")
			(hide yes)
			(effects
				(font
					(size 1 1)
					(thickness 0.15)
				)
				(justify mirror)
			)
		)
		(property "Val" "100n"
			(at 12.26 267.288 0)
			(layer "B.Fab")
			(hide yes)
			(effects
				(font
					(size 1 1)
					(thickness 0.15)
				)
				(justify mirror)
			)
		)
		(property "Voltage" ""
			(at 12.26 267.288 0)
			(layer "B.Fab")
			(hide yes)
			(effects
				(font
					(size 1 1)
					(thickness 0.15)
				)
				(justify mirror)
			)
		)
		(sheetname "/Interfaces/")
		(sheetfile "interfaces.kicad_sch")
		(attr smd)
		(fp_rect
			(start -0.925 0.47)
			(end 0.925 -0.47)
			(stroke
				(width 0.05)
				(type default)
			)
			(fill no)
			(layer "B.CrtYd")
		)
		(fp_line
			(start -0.494 0.25)
			(end 0.504 0.25)
			(stroke
				(width 0.15)
				(type solid)
			)
			(layer "B.Fab")
		)
		(fp_line
			(start 0.504 0.25)
			(end 0.504 -0.248)
			(stroke
				(width 0.15)
				(type solid)
			)
			(layer "B.Fab")
		)
		(fp_line
			(start -0.494 -0.248)
			(end -0.494 0.25)
			(stroke
				(width 0.15)
				(type solid)
			)
			(layer "B.Fab")
		)
		(fp_line
			(start 0.504 -0.248)
			(end -0.494 -0.248)
			(stroke
				(width 0.15)
				(type solid)
			)
			(layer "B.Fab")
		)
		(pad "1" smd roundrect
			(at -0.48 0 270)
			(size 0.59 0.64)
			(layers "B.Cu" "B.Mask" "B.Paste")
			(roundrect_rratio 0.25)
			(net 1 "GND")
			(pintype "passive")
		)
		(pad "2" smd roundrect
			(at 0.48 0 270)
			(size 0.59 0.64)
			(layers "B.Cu" "B.Mask" "B.Paste")
			(roundrect_rratio 0.25)
			(net 2 "VCC3V3")
			(pintype "passive")
		)
	)
	(footprint "antmicro-footprints:C_0402_1005Metric"
		(layer "B.Cu")
		(at 137.774 127.514 -90)
		(descr "Capacitor SMD 0402")
		(tags "capacitor SMD 0402")
		(property "Reference" "C230"
			(at 1.086 2.974 90)
			(layer "B.SilkS")
			(effects
				(font
					(size 0.7 0.7)
					(thickness 0.15)
				)
				(justify left bottom mirror)
			)
		)
		(property "Value" "C_100n_6V3_0402"
			(at 0 -1.4 90)
			(layer "B.Fab")
			(effects
				(font
					(size 0.7 0.7)
					(thickness 0.15)
				)
				(justify left bottom mirror)
			)
		)
		(property "Datasheet" "https://www.passivecomponent.com/wp-content/uploads/datasheet/WTC_MLCC_General_Purpose.pdf"
			(at 0 0 270)
			(layer "F.Fab")
			(hide yes)
			(effects
				(font
					(size 1.27 1.27)
					(thickness 0.15)
				)
			)
		)
		(property "Description" "SMT Multilayer Ceramic Capacitor, 0.1 µF, 6.3 V, 0402 [1005 Metric], ± 10%, X5R, Walsin MLCC"
			(at 0 0 270)
			(layer "F.Fab")
			(hide yes)
			(effects
				(font
					(size 1.27 1.27)
					(thickness 0.15)
				)
			)
		)
		(property "Author" "Antmicro"
			(at 10.26 265.288 0)
			(layer "B.Fab")
			(hide yes)
			(effects
				(font
					(size 1 1)
					(thickness 0.15)
				)
				(justify mirror)
			)
		)
		(property "Dielectric" ""
			(at 10.26 265.288 0)
			(layer "B.Fab")
			(hide yes)
			(effects
				(font
					(size 1 1)
					(thickness 0.15)
				)
				(justify mirror)
			)
		)
		(property "License" "Apache-2.0"
			(at 10.26 265.288 0)
			(layer "B.Fab")
			(hide yes)
			(effects
				(font
					(size 1 1)
					(thickness 0.15)
				)
				(justify mirror)
			)
		)
		(property "MPN" "0402X104K6R3CT"
			(at 10.26 265.288 0)
			(layer "B.Fab")
			(hide yes)
			(effects
				(font
					(size 1 1)
					(thickness 0.15)
				)
				(justify mirror)
			)
		)
		(property "Manufacturer" "Walsin"
			(at 10.26 265.288 0)
			(layer "B.Fab")
			(hide yes)
			(effects
				(font
					(size 1 1)
					(thickness 0.15)
				)
				(justify mirror)
			)
		)
		(property "Public" "False"
			(at 10.26 265.288 0)
			(layer "B.Fab")
			(hide yes)
			(effects
				(font
					(size 1 1)
					(thickness 0.15)
				)
				(justify mirror)
			)
		)
		(property "Val" "100n"
			(at 10.26 265.288 0)
			(layer "B.Fab")
			(hide yes)
			(effects
				(font
					(size 1 1)
					(thickness 0.15)
				)
				(justify mirror)
			)
		)
		(property "Voltage" ""
			(at 10.26 265.288 0)
			(layer "B.Fab")
			(hide yes)
			(effects
				(font
					(size 1 1)
					(thickness 0.15)
				)
				(justify mirror)
			)
		)
		(sheetname "/Interfaces/")
		(sheetfile "interfaces.kicad_sch")
		(attr smd)
		(fp_rect
			(start -0.925 0.47)
			(end 0.925 -0.47)
			(stroke
				(width 0.05)
				(type default)
			)
			(fill no)
			(layer "B.CrtYd")
		)
		(fp_line
			(start -0.494 0.25)
			(end 0.504 0.25)
			(stroke
				(width 0.15)
				(type solid)
			)
			(layer "B.Fab")
		)
		(fp_line
			(start 0.504 0.25)
			(end 0.504 -0.248)
			(stroke
				(width 0.15)
				(type solid)
			)
			(layer "B.Fab")
		)
		(fp_line
			(start -0.494 -0.248)
			(end -0.494 0.25)
			(stroke
				(width 0.15)
				(type solid)
			)
			(layer "B.Fab")
		)
		(fp_line
			(start 0.504 -0.248)
			(end -0.494 -0.248)
			(stroke
				(width 0.15)
				(type solid)
			)
			(layer "B.Fab")
		)
		(pad "1" smd roundrect
			(at -0.48 0 270)
			(size 0.59 0.64)
			(layers "B.Cu" "B.Mask" "B.Paste")
			(roundrect_rratio 0.25)
			(net 1 "GND")
			(pintype "passive")
		)
		(pad "2" smd roundrect
			(at 0.48 0 270)
			(size 0.59 0.64)
			(layers "B.Cu" "B.Mask" "B.Paste")
			(roundrect_rratio 0.25)
			(net 2 "VCC3V3")
			(pintype "passive")
		)
	)
)
